# Bryce Canyon_Storage_Controller_Card_Stackup.xlsx — PCB Test Plan_HVM(90+) (pcb-stackup)
|  | Board vendor give feedback of quantity in yellow columns based on the AQL table or description. |  |  |  |  |  |  |  |  |  |  |  |  |  |  |
|  | Wiwynn PM give feedback in blue columns |  |  |  |  |  |  |  |  |  |  |  |  |  |  |
| Person to be informed : PCB vendor, EE, SI, PM, PSM, Buyer, SQM |  |  |  |  |  |  |  |  |  |  |  |  |  |  |  |
| Simple flow : SI (test requirements) -> PM/AM (Total PCBS demand) -> Buyer -> Board Vendor (yellow column feedback) -> Buyer -> Person to be informed (Check and Track) |  |  |  |  |  |  |  |  |  |  |  |  |  |  |  |
| PO(purchase order) : If there are many POs for this PCB, 1st sample quantity is based on 1st PO, 2nd sample quantity is based on 2nd PO. |  |  |  |  |  |  |  |  |  |  |  |  |  |  |  |
| Project Name | PCB name | PCB# (1XXXX-XX) | Product Stage | Batch# | PCB Vendor | Production  Lot size | PCBs Demand | Delta-L Coupon (PCB Vendor) | Delta-L Coupon (3rd Party Lab) | Impedance Coupon (PCB Vendor) | In-board trace correlation (PCB Vendor) | X-section Analysis (PCB Vendor) | IST (3rd Party Lab) | IPC-6012D (3rd Party Lab) | Note |
| Bryce Canyon | FDPB | 16315-1 | HVM(90+ days) | N/A |  |  | TBD | Yes | No | Yes | No | No | No | No | Need Test? (Yes, No) |
| Tracking Code On Both Of Coupon And PCB |  |  |  |  |  |  |  | N/A |  | N/A |  |  |  |  |  |
| Test Item Acceptance Criteria |  |  |  |  |  |  |  | c = 0 |  | c = 0 |  |  |  |  |  |
| Test Item Sampling Quantity |  |  |  |  |  |  |  | 5 pcs/production lot/quarter, with max total of 30 pcs |  | Mil-STD 105E single sampling plan, AQL 0.65, level 2 |  |  |  |  |  |
| Test Time(working days) |  |  |  |  |  |  |  |  |  |  |  |  |  |  |  |
| Test Item Shipping Quantity |  |  |  |  |  |  |  |  |  |  |  |  |  |  |  |
| Shipping Address |  |  |  |  |  |  |  |  |  |  |  |  |  |  |  |
| Receiver Name |  |  |  |  |  |  |  |  |  |  |  |  |  |  |  |
| Receiver Phone# |  |  |  |  |  |  |  |  |  |  |  |  |  |  |  |
| Project Name | PCB name | PCB# (1XXXX-XX) | Product Stage | Batch# | PCB Vendor | Production  Lot size | PCBs Demand | Delta-L Coupon (PCB Vendor) | Delta-L Coupon (3rd Party Lab) | Impedance Coupon (PCB Vendor) | In-board trace correlation (PCB Vendor) | X-section Analysis (PCB Vendor) | IST (3rd Party Lab) | IPC-6012D (3rd Party Lab) | Note |
| Bryce Canyon | SCC | 16316-1 | HVM(90+ days) | N/A |  |  | TBD | No | No | Yes | No | No | No | No | Need Test? (Yes, No) |
| Tracking Code On Both Of Coupon And PCB |  |  |  |  |  |  |  |  |  | N/A |  |  |  |  |  |
| Test Item Acceptance Criteria |  |  |  |  |  |  |  |  |  | c = 0 |  |  |  |  |  |
| Test Item Sampling Quantity |  |  |  |  |  |  |  |  |  | Mil-STD 105E single sampling plan, AQL 0.65, level 2 |  |  |  |  |  |
| Test Time (working days) |  |  |  |  |  |  |  |  |  |  |  |  |  |  |  |
| Test Item Shipping Quantity |  |  |  |  |  |  |  |  |  |  |  |  |  |  |  |
| Shipping Address |  |  |  |  |  |  |  |  |  |  |  |  |  |  |  |
| Receiver Name |  |  |  |  |  |  |  |  |  |  |  |  |  |  |  |
| Receiver Phone# |  |  |  |  |  |  |  |  |  |  |  |  |  |  |  |
| Project Name | PCB name | PCB# (1XXXX-XX) | Product Stage | Batch# | PCB Vendor | Production  Lot size | PCBs Demand | Delta-L Coupon (PCB Vendor) | Delta-L Coupon (3rd Party Lab) | Impedance Coupon (PCB Vendor) | In-board trace correlation (PCB Vendor) | X-section Analysis (PCB Vendor) | IST (3rd Party Lab) | IPC-6012D (3rd Party Lab) | Note |
| Bryce Canyon | RDPB | 16317-1 | HVM(90+ days) | N/A |  |  | TBD | Yes | No | Yes | No | No | No | No | Need Test? (Yes, No) |
| Tracking Code On Both Of Coupon And PCB |  |  |  |  |  |  |  | N/A |  | N/A |  |  |  |  |  |
| Test Item Acceptance Criteria |  |  |  |  |  |  |  | c = 0 |  | c = 0 |  |  |  |  |  |
| Test Item Sampling Quantity |  |  |  |  |  |  |  | 5 pcs/production lot/quarter, with max total of 30 pcs |  | Mil-STD 105E single sampling plan, AQL 0.65, level 2 |  |  |  |  |  |
| Test Time (working days) |  |  |  |  |  |  |  |  |  |  |  |  |  |  |  |
| Test Item Shipping Quantity |  |  |  |  |  |  |  |  |  |  |  |  |  |  |  |
| Shipping Address |  |  |  |  |  |  |  |  |  |  |  |  |  |  |  |
| Receiver Name |  |  |  |  |  |  |  |  |  |  |  |  |  |  |  |
| Receiver Phone# |  |  |  |  |  |  |  |  |  |  |  |  |  |  |  |
| Project Name | PCB name | PCB# (1XXXX-XX) | Product Stage | Batch# | PCB Vendor | Production  Lot size | PCBs Demand | Delta-L Coupon (PCB Vendor) | Delta-L Coupon (3rd Party Lab) | Impedance Coupon (PCB Vendor) | In-board trace correlation (PCB Vendor) | X-section Analysis (PCB Vendor) | IST (3rd Party Lab) | IPC-6012D (3rd Party Lab) | Note |
| Bryce Canyon | IOM IOC | 16318-1 | HVM(90+ days) | N/A |  |  | TBD | No | No | Yes | No | No | No | No | Need Test? (Yes, No) |
| Tracking Code On Both Of Coupon And PCB |  |  |  |  |  |  |  |  |  | N/A |  |  |  |  |  |
| Test Item Acceptance Criteria |  |  |  |  |  |  |  |  |  | c = 0 |  |  |  |  |  |
| Test Item Sampling Quantity |  |  |  |  |  |  |  |  |  | Mil-STD 105E single sampling plan, AQL 0.65, level 2 |  |  |  |  |  |
| Test Time (working days) |  |  |  |  |  |  |  |  |  |  |  |  |  |  |  |
| Test Item Shipping Quantity |  |  |  |  |  |  |  |  |  |  |  |  |  |  |  |
| Shipping Address |  |  |  |  |  |  |  |  |  |  |  |  |  |  |  |
| Receiver Name |  |  |  |  |  |  |  |  |  |  |  |  |  |  |  |
| Receiver Phone# |  |  |  |  |  |  |  |  |  |  |  |  |  |  |  |
| Project Name | PCB name | PCB# (1XXXX-XX) | Product Stage | Batch# | PCB Vendor | Production  Lot size | PCBs Demand | Delta-L Coupon (PCB Vendor) | Delta-L Coupon (3rd Party Lab) | Impedance Coupon (PCB Vendor) | In-board trace correlation (PCB Vendor) | X-section Analysis (PCB Vendor) | IST (3rd Party Lab) | IPC-6012D (3rd Party Lab) | Note |
| Bryce Canyon | IOM M2 | 16342-1 | HVM(90+ days) | N/A |  |  | TBD | No | No | Yes | No | No | No | No | Need Test? (Yes, No) |
| Tracking Code On Both Of Coupon And PCB |  |  |  |  |  |  |  |  |  | N/A |  |  |  |  |  |
| Test Item Acceptance Criteria |  |  |  |  |  |  |  |  |  | c = 0 |  |  |  |  |  |
| Test Item Sampling Quantity |  |  |  |  |  |  |  |  |  | Mil-STD 105E single sampling plan, AQL 0.65, level 2 |  |  |  |  |  |
| Test Time (working days) |  |  |  |  |  |  |  |  |  |  |  |  |  |  |  |
| Test Item Shipping Quantity |  |  |  |  |  |  |  |  |  |  |  |  |  |  |  |
| Shipping Address |  |  |  |  |  |  |  |  |  |  |  |  |  |  |  |
| Receiver Name |  |  |  |  |  |  |  |  |  |  |  |  |  |  |  |
| Receiver Phone# |  |  |  |  |  |  |  |  |  |  |  |  |  |  |  |
